# T6G (Grand Teton) — schematic netlist excerpt (pin names and nets, part order shuffled) for the footprints in the layout excerpt that follows; sources: Cadence DE-HDL packaged netlist, KiCad conversion of 04192023_DAF0TMB3IC0_F0TG_MB_C_brd_V02_OCP.brd

R6824  Q_RES  0 5% CHIP  pkg 0402LF  page 81 : A = RST_RT_CPU0_P2_RESET_R2_N ; B = RST_RT_CPU0_P2_RESET_R_N
R6758  Q_RES  0 5% CHIP  pkg 0201LF  page 184 : A = SMB_RT_CPU0_P3_SDA ; B = SMB_RT_CPU0_P3_R_SDA
C2632  Q_CAP  22UF 4V 20% X6S  pkg C0402  page 70 : A = PVDDIO_P0 ; B = GND

(kicad_pcb
	(version 20260206)
	(generator "pcbnew")
	(generator_version "10.0")
	(general
		(thickness 1.6)
		(legacy_teardrops no)
	)
	(paper "A4")
	(title_block
		(title "04192023_DAF0TMB3IC0_F0TG_MB_C_brd_V02_OCP.brd")
		(comment 1 "Grand Teton / footprints 7514-7516 of 8354")
	)
	(layers
		(0 "F.Cu" signal "TOP")
		(4 "In1.Cu" signal "GND")
		(6 "In2.Cu" signal "IN1")
		(8 "In3.Cu" signal "GND1")
		(10 "In4.Cu" signal "IN2")
		(12 "In5.Cu" signal "GND2")
		(14 "In6.Cu" signal "IN3")
		(16 "In7.Cu" signal "GND3")
		(18 "In8.Cu" signal "VCC")
		(20 "In9.Cu" signal "VCC1")
		(22 "In10.Cu" signal "GND4")
		(24 "In11.Cu" signal "IN4")
		(26 "In12.Cu" signal "GND5")
		(28 "In13.Cu" signal "IN5")
		(30 "In14.Cu" signal "GND6")
		(32 "In15.Cu" signal "IN6")
		(34 "In16.Cu" signal "GND7")
		(2 "B.Cu" signal "BOTTOM")
		(9 "F.Adhes" user "F.Adhesive")
		(11 "B.Adhes" user "B.Adhesive")
		(13 "F.Paste" user "Package Geometry/Pastemask Top")
		(15 "B.Paste" user "Package Geometry/Pastemask Bottom")
		(5 "F.SilkS" user "Ref Des/Silkscreen Top")
		(7 "B.SilkS" user "Ref Des/Silkscreen Bottom")
		(1 "F.Mask" user "Board Geometry/Soldermask Top")
		(3 "B.Mask" user "Board Geometry/Soldermask Bottom")
		(17 "Dwgs.User" user "User.Drawings")
		(19 "Cmts.User" user "User.Comments")
		(21 "Eco1.User" user "User.Eco1")
		(23 "Eco2.User" user "User.Eco2")
		(25 "Edge.Cuts" user "Board Geometry/Outline")
		(27 "Margin" user)
		(31 "F.CrtYd" user "Package Geometry/Place Bound Top")
		(29 "B.CrtYd" user "Package Geometry/Place Bound Bottom")
		(35 "F.Fab" user "Ref Des/Assembly Top")
		(33 "B.Fab" user "Ref Des/Assembly Bottom")
	)
	(footprint ""
		(layer "B.Cu")
		(at 348.418912 -258.830064 180)
		(property "Reference" "C2632"
			(at 0 0 0)
			(layer "B.SilkS")
			(hide yes)
			(effects
				(font
					(size 1.27 1.27)
				)
				(justify mirror)
			)
		)
		(property "Value" ""
			(at 0 0 0)
			(layer "B.Fab")
			(effects
				(font
					(size 1.27 1.27)
				)
				(justify mirror)
			)
		)
		(duplicate_pad_numbers_are_jumpers no)
		(fp_line
			(start 0.7874 0.4064)
			(end 0.7874 -0.4064)
			(stroke
				(width 0.1524)
				(type default)
			)
			(layer "B.SilkS")
		)
		(fp_line
			(start 0.7874 -0.4064)
			(end -0.7874 -0.4064)
			(stroke
				(width 0.1524)
				(type default)
			)
			(layer "B.SilkS")
		)
		(fp_line
			(start -0.7874 0.4064)
			(end 0.7874 0.4064)
			(stroke
				(width 0.1524)
				(type default)
			)
			(layer "B.SilkS")
		)
		(fp_line
			(start -0.7874 -0.4064)
			(end -0.7874 0.4064)
			(stroke
				(width 0.1524)
				(type default)
			)
			(layer "B.SilkS")
		)
		(fp_line
			(start 0.67945 0.3048)
			(end 0.67945 -0.305054)
			(stroke
				(width 0.1)
				(type default)
			)
			(layer "B.Fab")
		)
		(fp_line
			(start 0.67945 -0.305054)
			(end 0.12065 -0.305054)
			(stroke
				(width 0.1)
				(type default)
			)
			(layer "B.Fab")
		)
		(fp_line
			(start 0.12065 0.3048)
			(end 0.67945 0.3048)
			(stroke
				(width 0.1)
				(type default)
			)
			(layer "B.Fab")
		)
		(fp_line
			(start 0.12065 0.2794)
			(end 0.12065 0.3048)
			(stroke
				(width 0.1)
				(type default)
			)
			(layer "B.Fab")
		)
		(fp_line
			(start 0.12065 -0.2794)
			(end -0.12065 -0.2794)
			(stroke
				(width 0.1)
				(type default)
			)
			(layer "B.Fab")
		)
		(fp_line
			(start 0.12065 -0.305054)
			(end 0.12065 -0.2794)
			(stroke
				(width 0.1)
				(type default)
			)
			(layer "B.Fab")
		)
		(fp_line
			(start -0.120396 0.3048)
			(end -0.120396 0.2794)
			(stroke
				(width 0.1)
				(type default)
			)
			(layer "B.Fab")
		)
		(fp_line
			(start -0.120396 0.2794)
			(end 0.12065 0.2794)
			(stroke
				(width 0.1)
				(type default)
			)
			(layer "B.Fab")
		)
		(fp_line
			(start -0.12065 -0.2794)
			(end -0.12065 -0.3048)
			(stroke
				(width 0.1)
				(type default)
			)
			(layer "B.Fab")
		)
		(fp_line
			(start -0.12065 -0.3048)
			(end -0.67945 -0.3048)
			(stroke
				(width 0.1)
				(type default)
			)
			(layer "B.Fab")
		)
		(fp_line
			(start -0.67945 0.3048)
			(end -0.120396 0.3048)
			(stroke
				(width 0.1)
				(type default)
			)
			(layer "B.Fab")
		)
		(fp_line
			(start -0.67945 -0.3048)
			(end -0.67945 0.3048)
			(stroke
				(width 0.1)
				(type default)
			)
			(layer "B.Fab")
		)
		(pad "1" smd circle
			(at 0.40005 0)
			(size 0 0)
			(layers "B.Cu" "B.Mask" "B.Paste")
			(net "PVDDIO_P0")
		)
		(pad "2" smd circle
			(at -0.40005 0)
			(size 0 0)
			(layers "B.Cu" "B.Mask" "B.Paste")
			(net "GND")
		)
	)
	(footprint ""
		(layer "B.Cu")
		(at 189.993778 -126.93396 -90)
		(property "Reference" "R6824"
			(at 0 0 90)
			(layer "B.SilkS")
			(hide yes)
			(effects
				(font
					(size 1.27 1.27)
				)
				(justify mirror)
			)
		)
		(property "Value" ""
			(at 0 0 90)
			(layer "B.Fab")
			(effects
				(font
					(size 1.27 1.27)
				)
				(justify mirror)
			)
		)
		(duplicate_pad_numbers_are_jumpers no)
		(fp_line
			(start -0.7874 0.4064)
			(end 0.7874 0.4064)
			(stroke
				(width 0.1524)
				(type default)
			)
			(layer "B.SilkS")
		)
		(fp_line
			(start 0.7874 0.4064)
			(end 0.7874 -0.4064)
			(stroke
				(width 0.1524)
				(type default)
			)
			(layer "B.SilkS")
		)
		(fp_line
			(start -0.7874 -0.4064)
			(end -0.7874 0.4064)
			(stroke
				(width 0.1524)
				(type default)
			)
			(layer "B.SilkS")
		)
		(fp_line
			(start 0.7874 -0.4064)
			(end -0.7874 -0.4064)
			(stroke
				(width 0.1524)
				(type default)
			)
			(layer "B.SilkS")
		)
		(fp_line
			(start -0.67945 0.3048)
			(end -0.120396 0.3048)
			(stroke
				(width 0.1)
				(type default)
			)
			(layer "B.Fab")
		)
		(fp_line
			(start -0.120396 0.3048)
			(end -0.120396 0.2794)
			(stroke
				(width 0.1)
				(type default)
			)
			(layer "B.Fab")
		)
		(fp_line
			(start 0.12065 0.3048)
			(end 0.67945 0.3048)
			(stroke
				(width 0.1)
				(type default)
			)
			(layer "B.Fab")
		)
		(fp_line
			(start 0.67945 0.3048)
			(end 0.67945 -0.305054)
			(stroke
				(width 0.1)
				(type default)
			)
			(layer "B.Fab")
		)
		(fp_line
			(start -0.120396 0.2794)
			(end 0.12065 0.2794)
			(stroke
				(width 0.1)
				(type default)
			)
			(layer "B.Fab")
		)
		(fp_line
			(start 0.12065 0.2794)
			(end 0.12065 0.3048)
			(stroke
				(width 0.1)
				(type default)
			)
			(layer "B.Fab")
		)
		(fp_line
			(start -0.12065 -0.2794)
			(end -0.12065 -0.3048)
			(stroke
				(width 0.1)
				(type default)
			)
			(layer "B.Fab")
		)
		(fp_line
			(start 0.12065 -0.2794)
			(end -0.12065 -0.2794)
			(stroke
				(width 0.1)
				(type default)
			)
			(layer "B.Fab")
		)
		(fp_line
			(start -0.67945 -0.3048)
			(end -0.67945 0.3048)
			(stroke
				(width 0.1)
				(type default)
			)
			(layer "B.Fab")
		)
		(fp_line
			(start -0.12065 -0.3048)
			(end -0.67945 -0.3048)
			(stroke
				(width 0.1)
				(type default)
			)
			(layer "B.Fab")
		)
		(fp_line
			(start 0.12065 -0.305054)
			(end 0.12065 -0.2794)
			(stroke
				(width 0.1)
				(type default)
			)
			(layer "B.Fab")
		)
		(fp_line
			(start 0.67945 -0.305054)
			(end 0.12065 -0.305054)
			(stroke
				(width 0.1)
				(type default)
			)
			(layer "B.Fab")
		)
		(pad "1" smd circle
			(at 0.40005 0 90)
			(size 0 0)
			(layers "B.Cu" "B.Mask" "B.Paste")
			(net "RST_RT_CPU0_P2_RESET_R2_N")
		)
		(pad "2" smd circle
			(at -0.40005 0 90)
			(size 0 0)
			(layers "B.Cu" "B.Mask" "B.Paste")
			(net "RST_RT_CPU0_P2_RESET_R_N")
		)
	)
	(footprint ""
		(layer "B.Cu")
		(at 229.8446 -337.312 180)
		(property "Reference" "R6758"
			(at 0 0 0)
			(layer "B.SilkS")
			(hide yes)
			(effects
				(font
					(size 1.27 1.27)
				)
				(justify mirror)
			)
		)
		(property "Value" ""
			(at 0 0 0)
			(layer "B.Fab")
			(effects
				(font
					(size 1.27 1.27)
				)
				(justify mirror)
			)
		)
		(duplicate_pad_numbers_are_jumpers no)
		(fp_line
			(start 0.32512 0.175006)
			(end 0.32512 -0.175006)
			(stroke
				(width 0.1)
				(type default)
			)
			(layer "B.Fab")
		)
		(fp_line
			(start 0.32512 -0.175006)
			(end -0.32512 -0.175006)
			(stroke
				(width 0.1)
				(type default)
			)
			(layer "B.Fab")
		)
		(fp_line
			(start -0.32512 0.175006)
			(end 0.32512 0.175006)
			(stroke
				(width 0.1)
				(type default)
			)
			(layer "B.Fab")
		)
		(fp_line
			(start -0.32512 -0.175006)
			(end -0.32512 0.175006)
			(stroke
				(width 0.1)
				(type default)
			)
			(layer "B.Fab")
		)
		(pad "1" smd rect
			(at 0.2667 0)
			(size 0.3048 0.381)
			(layers "B.Cu" "B.Mask" "B.Paste")
			(net "SMB_RT_CPU0_P3_SDA")
		)
		(pad "2" smd rect
			(at -0.2667 0 180)
			(size 0.3048 0.381)
			(layers "B.Cu" "B.Mask" "B.Paste")
			(net "SMB_RT_CPU0_P3_R_SDA")
		)
	)
)
